(kicad_pcb
	(version 20260206)
	(generator "pcbnew")
	(generator_version "10.0")
	(general
		(thickness 1.6)
		(legacy_teardrops no)
	)
	(paper "A4")
	(title_block
		(title "Bryce Canyon_F.DPB_16315-1-OCP.brd")
		(comment 1 "Bryce Canyon / footprints 1609-1611 of 2223")
	)
	(layers
		(0 "F.Cu" signal "TOP")
		(4 "In1.Cu" signal "L2GND")
		(6 "In2.Cu" signal "L3")
		(8 "In3.Cu" signal "L4GND")
		(10 "In4.Cu" signal "L5")
		(12 "In5.Cu" signal "L6VCC")
		(14 "In6.Cu" signal "L7VCC")
		(16 "In7.Cu" signal "L8")
		(18 "In8.Cu" signal "L9GND")
		(20 "In9.Cu" signal "L10")
		(22 "In10.Cu" signal "L11GND")
		(2 "B.Cu" signal "BOTTOM")
		(9 "F.Adhes" user "F.Adhesive")
		(11 "B.Adhes" user "B.Adhesive")
		(13 "F.Paste" user "Package Geometry/Pastemask Top")
		(15 "B.Paste" user "Package Geometry/Pastemask Bottom")
		(5 "F.SilkS" user "Ref Des/Silkscreen Top")
		(7 "B.SilkS" user "Ref Des/Silkscreen Bottom")
		(1 "F.Mask" user "Board Geometry/Soldermask Top")
		(3 "B.Mask" user "Board Geometry/Soldermask Bottom")
		(17 "Dwgs.User" user "User.Drawings")
		(19 "Cmts.User" user "User.Comments")
		(21 "Eco1.User" user "User.Eco1")
		(23 "Eco2.User" user "User.Eco2")
		(25 "Edge.Cuts" user "Board Geometry/Outline")
		(27 "Margin" user)
		(31 "F.CrtYd" user "Package Geometry/Place Bound Top")
		(29 "B.CrtYd" user "Package Geometry/Place Bound Bottom")
		(35 "F.Fab" user "Ref Des/Assembly Top")
		(33 "B.Fab" user "Ref Des/Assembly Bottom")
	)
	(footprint ""
		(layer "F.Cu")
		(at 81.51495 -242.25377)
		(property "Reference" "R218"
			(at 0 0 0)
			(layer "F.SilkS")
			(hide yes)
			(effects
				(font
					(size 1.27 1.27)
				)
			)
		)
		(property "Value" "91R3F-1-GP"
			(at -0.0254 -2.5146 0)
			(unlocked yes)
			(layer "F.Fab")
			(hide yes)
			(effects
				(font
					(size 1.016 1.016)
					(thickness 0.1524)
				)
			)
		)
		(property "Device Type" "R603H22"
			(at -0.0254 -4.0386 0)
			(unlocked yes)
			(layer "F.Fab")
			(hide yes)
			(effects
				(font
					(size 1.016 1.016)
					(thickness 0.1524)
				)
			)
		)
		(duplicate_pad_numbers_are_jumpers no)
		(fp_line
			(start -0.4826 0)
			(end -0.2032 0)
			(stroke
				(width 0.2032)
				(type default)
			)
			(layer "F.SilkS")
		)
		(fp_line
			(start 0.2032 0)
			(end 0.4826 0)
			(stroke
				(width 0.2032)
				(type default)
			)
			(layer "F.SilkS")
		)
		(fp_rect
			(start -0.5842 1.3335)
			(end 0.5842 -1.3335)
			(stroke
				(width 0)
				(type default)
			)
			(fill no)
			(layer "F.CrtYd")
		)
		(fp_rect
			(start -0.5842 1.3335)
			(end 0.5842 -1.3335)
			(stroke
				(width 0)
				(type default)
			)
			(fill no)
			(layer "F.Fab")
		)
		(pad "1" smd custom
			(at 0 -0.762)
			(size 0.2159 0.2159)
			(layers "F.Cu" "F.Mask" "F.Paste")
			(net "P5V_A_1")
			(options
				(clearance outline)
				(anchor circle)
			)
			(primitives
				(gr_poly
					(pts
						(arc
							(start -0.3302 -0.4318)
							(mid -0.402042 -0.402042)
							(end -0.4318 -0.3302)
						)
						(arc
							(start -0.4318 0.3302)
							(mid -0.402042 0.402042)
							(end -0.3302 0.4318)
						)
						(arc
							(start 0.3302 0.4318)
							(mid 0.402042 0.402042)
							(end 0.4318 0.3302)
						)
						(arc
							(start 0.4318 -0.3302)
							(mid 0.402042 -0.402042)
							(end 0.3302 -0.4318)
						)
					)
					(width 0)
					(fill yes)
				)
			)
		)
		(pad "2" smd custom
			(at 0 0.762)
			(size 0.2159 0.2159)
			(layers "F.Cu" "F.Mask" "F.Paste")
			(net "DRV_ACT_2")
			(options
				(clearance outline)
				(anchor circle)
			)
			(primitives
				(gr_poly
					(pts
						(arc
							(start -0.3302 -0.4318)
							(mid -0.402042 -0.402042)
							(end -0.4318 -0.3302)
						)
						(arc
							(start -0.4318 0.3302)
							(mid -0.402042 0.402042)
							(end -0.3302 0.4318)
						)
						(arc
							(start 0.3302 0.4318)
							(mid 0.402042 0.402042)
							(end 0.4318 0.3302)
						)
						(arc
							(start 0.4318 -0.3302)
							(mid 0.402042 -0.402042)
							(end 0.3302 -0.4318)
						)
					)
					(width 0)
					(fill yes)
				)
			)
		)
	)
	(footprint ""
		(layer "F.Cu")
		(at 420.200074 -57.909968 -90)
		(property "Reference" "HDDSAS33"
			(at 0 0 270)
			(layer "F.SilkS")
			(hide yes)
			(effects
				(font
					(size 1.27 1.27)
				)
			)
		)
		(property "Value" "SKT-SAS15P-14P-45-GP"
			(at -20.7645 -8.9789 270)
			(unlocked yes)
			(layer "F.Fab")
			(hide yes)
			(effects
				(font
					(size 1.016 1.016)
					(thickness 0.1524)
				)
			)
		)
		(property "Device Type" "10120818-001C-TRLF"
			(at -20.7645 -10.5029 270)
			(unlocked yes)
			(layer "F.Fab")
			(hide yes)
			(effects
				(font
					(size 1.016 1.016)
					(thickness 0.1524)
				)
			)
		)
		(duplicate_pad_numbers_are_jumpers no)
		(fp_line
			(start 1.651 4.2926)
			(end 1.651 3.0099)
			(stroke
				(width 0.1524)
				(type default)
			)
			(layer "F.SilkS")
		)
		(fp_line
			(start 8.509 4.2926)
			(end 1.651 4.2926)
			(stroke
				(width 0.1524)
				(type default)
			)
			(layer "F.SilkS")
		)
		(fp_line
			(start -23.4188 3.0099)
			(end -23.4188 -3.2512)
			(stroke
				(width 0.1524)
				(type default)
			)
			(layer "F.SilkS")
		)
		(fp_line
			(start 1.651 3.0099)
			(end -23.4188 3.0099)
			(stroke
				(width 0.1524)
				(type default)
			)
			(layer "F.SilkS")
		)
		(fp_line
			(start 8.509 3.0099)
			(end 8.509 4.2926)
			(stroke
				(width 0.1524)
				(type default)
			)
			(layer "F.SilkS")
		)
		(fp_line
			(start 23.4188 3.0099)
			(end 8.509 3.0099)
			(stroke
				(width 0.1524)
				(type default)
			)
			(layer "F.SilkS")
		)
		(fp_line
			(start -23.4188 -3.2512)
			(end 23.4188 -3.2512)
			(stroke
				(width 0.1524)
				(type default)
			)
			(layer "F.SilkS")
		)
		(fp_line
			(start 23.4188 -3.2512)
			(end 23.4188 3.0099)
			(stroke
				(width 0.1524)
				(type default)
			)
			(layer "F.SilkS")
		)
		(fp_line
			(start 15.5067 -3.3401)
			(end 16.2687 -3.3401)
			(stroke
				(width 0.3302)
				(type default)
			)
			(layer "F.SilkS")
		)
		(fp_poly
			(pts
				(xy 15.868904 -3.230372) (xy 16.503904 -3.865372) (xy 15.233904 -3.865372)
			)
			(stroke
				(width 0)
				(type default)
			)
			(fill yes)
			(layer "F.SilkS")
		)
		(fp_poly
			(pts
				(xy -22.8727 -2.7559) (xy 22.8727 -2.7559) (xy 22.8727 2.7559) (xy 8.255 2.7559) (xy 8.255 3.5179)
				(xy 1.905 3.5179) (xy 1.905 2.7559) (xy -22.8727 2.7559)
			)
			(stroke
				(width 0)
				(type default)
			)
			(fill no)
			(layer "F.CrtYd")
		)
		(fp_poly
			(pts
				(xy 1.397 4.5466) (xy 1.397 3.2639) (xy -23.6728 3.2639) (xy -23.6728 -3.5052) (xy 23.6728 -3.5052)
				(xy 23.6728 -0.00635) (xy 22.8727 -0.00635) (xy 22.8727 -2.7559) (xy -22.8727 -2.7559) (xy -22.8727 2.7559)
				(xy 1.905 2.7559) (xy 1.905 3.5179) (xy 8.255 3.5179) (xy 8.255 2.7559) (xy 22.8727 2.7559) (xy 22.8727 0.00635)
				(xy 23.6728 0.00635) (xy 23.6728 3.2639) (xy 8.763 3.2639) (xy 8.763 4.5466)
			)
			(stroke
				(width 0)
				(type default)
			)
			(fill no)
			(layer "F.CrtYd")
		)
		(fp_poly
			(pts
				(xy 1.397 4.5466) (xy 1.397 3.2639) (xy -23.6728 3.2639) (xy -23.6728 -3.5052) (xy 23.6728 -3.5052)
				(xy 23.6728 3.2639) (xy 8.763 3.2639) (xy 8.763 4.5466)
			)
			(stroke
				(width 0)
				(type default)
			)
			(fill no)
			(layer "F.Fab")
		)
		(pad "" np_thru_hole circle
			(at -18.874994 0 270)
			(size 0.254 0.254)
			(drill 1.3462)
			(layers "*.Cu" "*.Mask")
			(clearance 0.9017)
			(thermal_gap 0.9017)
		)
		(pad "" np_thru_hole circle
			(at 18.874994 0 270)
			(size 0.254 0.254)
			(drill 0.9398)
			(layers "*.Cu" "*.Mask")
			(clearance 0.6985)
			(thermal_gap 0.6985)
		)
		(pad "G1" smd rect
			(at 21.874988 0 270)
			(size 2.5908 2.5908)
			(layers "F.Cu" "F.Mask" "F.Paste")
			(net "GND")
		)
		(pad "G2" smd rect
			(at -21.874988 0 270)
			(size 2.5908 2.5908)
			(layers "F.Cu" "F.Mask" "F.Paste")
			(net "GND")
		)
		(pad "P1" smd rect
			(at 1.905 -1.82499 270)
			(size 0.6096 2.3622)
			(layers "F.Cu" "F.Mask" "F.Paste")
			(net "Net_2041")
		)
		(pad "P2" smd rect
			(at 0.635 -1.82499 270)
			(size 0.6096 2.3622)
			(layers "F.Cu" "F.Mask" "F.Paste")
			(net "Net_2042")
		)
		(pad "P3" smd rect
			(at -0.635 -1.82499 270)
			(size 0.6096 2.3622)
			(layers "F.Cu" "F.Mask" "F.Paste")
			(net "Net_2043")
		)
		(pad "P4" smd rect
			(at -1.905 -1.82499 270)
			(size 0.6096 2.3622)
			(layers "F.Cu" "F.Mask" "F.Paste")
			(net "GND")
		)
		(pad "P5" smd rect
			(at -3.175 -1.82499 270)
			(size 0.6096 2.3622)
			(layers "F.Cu" "F.Mask" "F.Paste")
			(net "HDD_PRSNT_33")
		)
		(pad "P6" smd rect
			(at -4.445 -1.82499 270)
			(size 0.6096 2.3622)
			(layers "F.Cu" "F.Mask" "F.Paste")
			(net "GND")
		)
		(pad "P7" smd rect
			(at -5.715 -1.82499 270)
			(size 0.6096 2.3622)
			(layers "F.Cu" "F.Mask" "F.Paste")
			(net "5V_PRE_33")
		)
		(pad "P8" smd rect
			(at -6.985 -1.82499 270)
			(size 0.6096 2.3622)
			(layers "F.Cu" "F.Mask" "F.Paste")
			(net "P5V_HDD33")
		)
		(pad "P9" smd rect
			(at -8.255 -1.82499 270)
			(size 0.6096 2.3622)
			(layers "F.Cu" "F.Mask" "F.Paste")
			(net "P5V_HDD33")
		)
		(pad "P10" smd rect
			(at -9.525 -1.82499 270)
			(size 0.6096 2.3622)
			(layers "F.Cu" "F.Mask" "F.Paste")
			(net "GND")
		)
		(pad "P11" smd rect
			(at -10.795 -1.82499 270)
			(size 0.6096 2.3622)
			(layers "F.Cu" "F.Mask" "F.Paste")
			(net "ACT_HDD_33")
		)
		(pad "P12" smd rect
			(at -12.065 -1.82499 270)
			(size 0.6096 2.3622)
			(layers "F.Cu" "F.Mask" "F.Paste")
			(net "GND")
		)
		(pad "P13" smd rect
			(at -13.335 -1.82499 270)
			(size 0.6096 2.3622)
			(layers "F.Cu" "F.Mask" "F.Paste")
			(net "12V_PRE_33")
		)
		(pad "P14" smd rect
			(at -14.605 -1.82499 270)
			(size 0.6096 2.3622)
			(layers "F.Cu" "F.Mask" "F.Paste")
			(net "P12V_HDD33")
		)
		(pad "P15" smd rect
			(at -15.875 -1.82499 270)
			(size 0.6096 2.3622)
			(layers "F.Cu" "F.Mask" "F.Paste")
			(net "P12V_HDD33")
		)
		(pad "S1" smd rect
			(at 15.875 -1.82499 270)
			(size 0.6096 2.3622)
			(layers "F.Cu" "F.Mask" "F.Paste")
			(net "GND")
		)
		(pad "S2" smd rect
			(at 14.605 -1.82499 270)
			(size 0.6096 2.3622)
			(layers "F.Cu" "F.Mask" "F.Paste")
			(net "SAS_HDD_RX_P33")
		)
		(pad "S3" smd rect
			(at 13.335 -1.82499 270)
			(size 0.6096 2.3622)
			(layers "F.Cu" "F.Mask" "F.Paste")
			(net "SAS_HDD_RX_N33")
		)
		(pad "S4" smd rect
			(at 12.065 -1.82499 270)
			(size 0.6096 2.3622)
			(layers "F.Cu" "F.Mask" "F.Paste")
			(net "GND")
		)
		(pad "S5" smd rect
			(at 10.795 -1.82499 270)
			(size 0.6096 2.3622)
			(layers "F.Cu" "F.Mask" "F.Paste")
			(net "PHY_DRV_A_TO_SCC_A_33_DN")
		)
		(pad "S6" smd rect
			(at 9.525 -1.82499 270)
			(size 0.6096 2.3622)
			(layers "F.Cu" "F.Mask" "F.Paste")
			(net "PHY_DRV_A_TO_SCC_A_33_DP")
		)
		(pad "S7" smd rect
			(at 8.255 -1.82499 270)
			(size 0.6096 2.3622)
			(layers "F.Cu" "F.Mask" "F.Paste")
			(net "GND")
		)
		(pad "S8" smd rect
			(at 7.480046 2.845054 270)
			(size 0.508 2.3622)
			(layers "F.Cu" "F.Mask" "F.Paste")
			(net "GND")
		)
		(pad "S9" smd rect
			(at 6.679946 2.845054 270)
			(size 0.508 2.3622)
			(layers "F.Cu" "F.Mask" "F.Paste")
			(net "Net_472")
		)
		(pad "S10" smd rect
			(at 5.8801 2.845054 270)
			(size 0.508 2.3622)
			(layers "F.Cu" "F.Mask" "F.Paste")
			(net "Net_364")
		)
		(pad "S11" smd rect
			(at 5.08 2.845054 270)
			(size 0.508 2.3622)
			(layers "F.Cu" "F.Mask" "F.Paste")
			(net "GND")
		)
		(pad "S12" smd rect
			(at 4.2799 2.845054 270)
			(size 0.508 2.3622)
			(layers "F.Cu" "F.Mask" "F.Paste")
			(net "Net_400")
		)
		(pad "S13" smd rect
			(at 3.480054 2.845054 270)
			(size 0.508 2.3622)
			(layers "F.Cu" "F.Mask" "F.Paste")
			(net "Net_436")
		)
		(pad "S14" smd rect
			(at 2.679954 2.845054 270)
			(size 0.508 2.3622)
			(layers "F.Cu" "F.Mask" "F.Paste")
			(net "GND")
		)
		(zone
			(layer "F.Cu")
			(hatch none 0.5)
			(connect_pads
				(clearance 0)
			)
			(min_thickness 0.25)
			(keepout
				(tracks not_allowed)
				(vias allowed)
				(pads allowed)
				(copperpour not_allowed)
				(footprints allowed)
			)
			(placement
				(enabled no)
				(sheetname "")
			)
			(fill
				(thermal_gap 0.5)
				(thermal_bridge_width 0.5)
				(island_removal_mode 0)
			)
			(polygon
				(pts
					(xy 423.857674 -74.648568) (xy 416.783774 -74.648568) (xy 416.783774 -81.582768) (xy 417.888674 -81.582768)
					(xy 417.888674 -77.467968) (xy 422.511474 -77.467968) (xy 422.511474 -81.582768) (xy 423.857674 -81.582768)
				)
			)
		)
		(zone
			(layer "F.Cu")
			(hatch none 0.5)
			(connect_pads
				(clearance 0)
			)
			(min_thickness 0.25)
			(keepout
				(tracks allowed)
				(vias not_allowed)
				(pads allowed)
				(copperpour not_allowed)
				(footprints allowed)
			)
			(placement
				(enabled no)
				(sheetname "")
			)
			(fill
				(thermal_gap 0.5)
				(thermal_bridge_width 0.5)
				(island_removal_mode 0)
			)
			(polygon
				(pts
					(xy 423.857674 -74.648568) (xy 416.783774 -74.648568) (xy 416.783774 -81.582768) (xy 417.888674 -81.582768)
					(xy 417.888674 -77.467968) (xy 422.511474 -77.467968) (xy 422.511474 -81.582768) (xy 423.857674 -81.582768)
				)
			)
		)
		(zone
			(layer "F.Cu")
			(hatch none 0.5)
			(connect_pads
				(clearance 0)
			)
			(min_thickness 0.25)
			(keepout
				(tracks not_allowed)
				(vias allowed)
				(pads allowed)
				(copperpour not_allowed)
				(footprints allowed)
			)
			(placement
				(enabled no)
				(sheetname "")
			)
			(fill
				(thermal_gap 0.5)
				(thermal_bridge_width 0.5)
				(island_removal_mode 0)
			)
			(polygon
				(pts
					(xy 423.857674 -41.171368) (xy 416.783774 -41.171368) (xy 416.783774 -34.237168) (xy 417.888674 -34.237168)
					(xy 417.888674 -38.351968) (xy 422.511474 -38.351968) (xy 422.511474 -34.237168) (xy 423.857674 -34.237168)
				)
			)
		)
		(zone
			(layer "F.Cu")
			(hatch none 0.5)
			(connect_pads
				(clearance 0)
			)
			(min_thickness 0.25)
			(keepout
				(tracks allowed)
				(vias not_allowed)
				(pads allowed)
				(copperpour not_allowed)
				(footprints allowed)
			)
			(placement
				(enabled no)
				(sheetname "")
			)
			(fill
				(thermal_gap 0.5)
				(thermal_bridge_width 0.5)
				(island_removal_mode 0)
			)
			(polygon
				(pts
					(xy 423.857674 -41.171368) (xy 416.783774 -41.171368) (xy 416.783774 -34.237168) (xy 417.888674 -34.237168)
					(xy 417.888674 -38.351968) (xy 422.511474 -38.351968) (xy 422.511474 -34.237168) (xy 423.857674 -34.237168)
				)
			)
		)
		(zone
			(layers "F.Cu" "B.Cu" "In1.Cu" "In2.Cu" "In3.Cu" "In4.Cu" "In5.Cu" "In6.Cu"
				"In7.Cu" "In8.Cu" "In9.Cu" "In10.Cu"
			)
			(hatch none 0.5)
			(connect_pads
				(clearance 0)
			)
			(min_thickness 0.25)
			(keepout
				(tracks not_allowed)
				(vias allowed)
				(pads allowed)
				(copperpour not_allowed)
				(footprints allowed)
			)
			(placement
				(enabled no)
				(sheetname "")
			)
			(fill
				(thermal_gap 0.5)
				(thermal_bridge_width 0.5)
				(island_removal_mode 0)
			)
			(polygon
				(pts
					(arc
						(start 420.974774 -39.034974)
						(mid 419.425374 -39.034974)
						(end 420.974774 -39.034974)
					)
				)
			)
		)
		(zone
			(layers "F.Cu" "B.Cu" "In1.Cu" "In2.Cu" "In3.Cu" "In4.Cu" "In5.Cu" "In6.Cu"
				"In7.Cu" "In8.Cu" "In9.Cu" "In10.Cu"
			)
			(hatch none 0.5)
			(connect_pads
				(clearance 0)
			)
			(min_thickness 0.25)
			(keepout
				(tracks not_allowed)
				(vias allowed)
				(pads allowed)
				(copperpour not_allowed)
				(footprints allowed)
			)
			(placement
				(enabled no)
				(sheetname "")
			)
			(fill
				(thermal_gap 0.5)
				(thermal_bridge_width 0.5)
				(island_removal_mode 0)
			)
			(polygon
				(pts
					(arc
						(start 421.177974 -76.784962)
						(mid 419.222174 -76.784962)
						(end 421.177974 -76.784962)
					)
				)
			)
		)
	)
	(footprint ""
		(layer "F.Cu")
		(at 240.578386 -346.351098 180)
		(property "Reference" "R168"
			(at 0 0 180)
			(layer "F.SilkS")
			(hide yes)
			(effects
				(font
					(size 1.27 1.27)
				)
			)
		)
		(property "Value" "10KR2F-2-GP"
			(at 0.064008 -3.993896 180)
			(unlocked yes)
			(layer "F.Fab")
			(hide yes)
			(effects
				(font
					(size 1.016 1.016)
					(thickness 0.1524)
				)
			)
		)
		(property "Device Type" "R402H16"
			(at 0.064008 -5.517896 180)
			(unlocked yes)
			(layer "F.Fab")
			(hide yes)
			(effects
				(font
					(size 1.016 1.016)
					(thickness 0.1524)
				)
			)
		)
		(duplicate_pad_numbers_are_jumpers no)
		(fp_line
			(start 0.508 -0.9398)
			(end -0.508 -0.9398)
			(stroke
				(width 0.1524)
				(type default)
			)
			(layer "F.SilkS")
		)
		(fp_line
			(start -0.508 -0.9398)
			(end -0.508 0.9398)
			(stroke
				(width 0.1524)
				(type default)
			)
			(layer "F.SilkS")
		)
		(fp_rect
			(start -0.508 0.9398)
			(end 0.508 -0.9398)
			(stroke
				(width 0)
				(type default)
			)
			(fill no)
			(layer "F.CrtYd")
		)
		(fp_rect
			(start -0.508 0.9398)
			(end 0.508 -0.9398)
			(stroke
				(width 0)
				(type default)
			)
			(fill no)
			(layer "F.Fab")
		)
		(pad "1" smd custom
			(at 0 -0.4445 180)
			(size 0.1397 0.1397)
			(layers "F.Cu" "F.Mask" "F.Paste")
			(net "P5V_A_3_SENSE")
			(options
				(clearance outline)
				(anchor circle)
			)
			(primitives
				(gr_poly
					(pts
						(arc
							(start -0.1778 -0.2794)
							(mid -0.249642 -0.249642)
							(end -0.2794 -0.1778)
						)
						(arc
							(start -0.2794 0.1778)
							(mid -0.249642 0.249642)
							(end -0.1778 0.2794)
						)
						(arc
							(start 0.1778 0.2794)
							(mid 0.249642 0.249642)
							(end 0.2794 0.1778)
						)
						(arc
							(start 0.2794 -0.1778)
							(mid 0.249642 -0.249642)
							(end 0.1778 -0.2794)
						)
					)
					(width 0)
					(fill yes)
				)
			)
		)
		(pad "2" smd custom
			(at 0 0.4445 180)
			(size 0.1397 0.1397)
			(layers "F.Cu" "F.Mask" "F.Paste")
			(net "GND")
			(options
				(clearance outline)
				(anchor circle)
			)
			(primitives
				(gr_poly
					(pts
						(arc
							(start -0.1778 -0.2794)
							(mid -0.249642 -0.249642)
							(end -0.2794 -0.1778)
						)
						(arc
							(start -0.2794 0.1778)
							(mid -0.249642 0.249642)
							(end -0.1778 0.2794)
						)
						(arc
							(start 0.1778 0.2794)
							(mid 0.249642 0.249642)
							(end 0.2794 0.1778)
						)
						(arc
							(start 0.2794 -0.1778)
							(mid 0.249642 -0.249642)
							(end 0.1778 -0.2794)
						)
					)
					(width 0)
					(fill yes)
				)
			)
		)
	)
)
